# GrandTeton_FIO_BOM_20230829.xlsx — 2nd_source (bom)
| Part Number | Quantity | Part Reference | Description | Manuftr | Manuf_PN | Manuf_name |
| CH6103ME902 | 2 | C1,C3 | CAP CHIP 10U 16V(+-20%,X6S,0603) | MUR | GRM188C81C106M | MURATA ERIE N.A. INC TAIWAN BRANCH Okayama Murata |
| CH4104K1B00 | 1 | C2 | CAP CHIP 0.1U 25V(+-10%,X7R,0402) | MUR | GRM155R71E104K | MURATA ERIE N.A. INC TAIWAN BRANCH Okayama Murata |
| CH4103K1B08 | 4 | C5,C7,C11 | CAP CHIP 0.1U 16V(10%.X7R.0402) | MUR | WBM155R71C104K | MURATA ERIE N.A. INC TAIWAN BRANCH Okayama Murata Mfg.Co..Ltd. Wakura Murata Mfg |
| CH11006JB00 | 1 | C6 | CAP CHIP 100P 50V(+-5%.NPO.0402) | RHT | CC0402N101J3SST-S | "RTECH TECHNOLOGY CO..LTD.(Compostar)" |
| CH6223MEA01 | 6 | C9,C10,C12,C14,C15,C16 | CAP CHIP 22UF 16V(+-20%,X6S,0805)MUR | MUR | GRM21BC81C226M | MURATA ERIE N.A. INC TAIWAN BRANCH Okayama Murata |
| CH5222KEB01 | 3 | C4,C8,C13 | CAP CHIP 2.2UF 10V(+-10%,X6S,0402) | MUR | GRM155C81A225K | MURATA ERIE N.A. INC TAIWAN BRANCH Okayama Murata |
| BEYL0186D00 | 1 | D2 | LED DIP(2P)YELLOW(HV-312470/260/UY-TR1) | HCK | HV-312470-260-UY-TR1 | HARVATEK |
| BEBL0277D00 | 1 | D3 | LED DIP(2P)BLUE(HV-312470/260/SUBD-TR1) | HCK | HV-312470-260-SUBD-TR1 | LITE-ON CORP.(LITE-ON IT CORPORATION) |
| DFHS38FR040 | 1 | J1 | CONN SMD HOUSING 38P 2R FR(P0.6,H6.6) | LTS | ASASS005-P201A | LOTES(CHIA TSE TERMINAL INDUSTRYLOTES SUZHOU CO.,LTD |
| DFHS09FR786 | 1 | J2 | CONN DIP USB3.0 9P 2R FR(P2.0,H14.5) | FOX | UEA191C-40025-7H | (FOXCONN) |
| BAM01380025 | 1 | Q1 | TRANS MOS NX138BKS(60V,0.21A,0.32W) | NXP | NX138BKS | NXP semiconductors |
| CS17503F902 | 1 | R1 | RES CHIP 750 1/10W +-1%(0603)EF | YGO | RC0603FR-07750RP | YAGEO CORPORATION |
| CS00002JB13 | 11 | R2,R4,R13,R14,R15,R51,R52,R65,R67,R68 | RES CHIP 0 1/16W +-5%(0402)EF | WTC | WR04X000PTR | WALSIN TECHNOLOGY CORPORATION |
| CS14704JA01 | 1 | R3 | RES CHIP 470 1/8W +-5%(0805)EF | WTC | WR08X471 JTR | WALSIN TECHNOLOGY CORPORATION |
| CS41002FB09 | 3 | R6,R8,R12 | RES CHIP 100K 1/16W +-1%(0402)EF | WTC | WR04X1003FTR | WALSIN TECHNOLOGY CORPORATION |
| CS13603F901 | 2 | R7,R11 | RES CHIP 360 1/10W +-1%(0603)EF | WTC | WR06X3600FTR | WALSIN TECHNOLOGY CORPORATION |
| CS24752FB03 | 1 | R10 | RES CHIP 4.75K 1/16W +-1%(0402)EF | WTC | WR04X4751FTR | WALSIN TECHNOLOGY CORPORATION |
| CS03322FB03 | 4 | R16,R17,R48,R49 | RES CHIP 33.2 1/16W +-1%(0402)EF | WTC | WR04X33R2FTR | WALSIN TECHNOLOGY CORPORATION |
| CS31002FB08 | 3 | R19,R20,R21 | RES CHIP 10K 1/16W +-1%(0402)EF | WTC | WR04X1002FTR | WALSIN TECHNOLOGY CORPORATION |
| CS31002JB08 | 7 | R23,R29,R40,R41,R61,R62,R64 | RES CHIP 10K 1/16W +-5%(0402)EF | WTC | WR04X103 JTR | WALSIN TECHNOLOGY CORPORATION |
| CS41002JB06 | 6 | R27,R37,R38,R39,R50 | RES CHIP 100K 1/16W +-5%(0402)EF | WTC | WR04X104 JTR | WALSIN TECHNOLOGY CORPORATION |
| CS03302JB10 | 2 | R35,R36 | RES CHIP 33 1/16W +-5%(0402)EF | WTC | WR04X330 JTR | WALSIN TECHNOLOGY CORPORATION |
| CS31822FB02 | 1 | R42 | RES CHIP 18.2K 1/16W +-1%(0402)EF | TAI | RM04FTW1822 | TA-I TECHNOLOGY CO.,LTD. |
| CS24702JB10 | 3 | R44,R45,R58 | RES CHIP 4.7K 1/16W +-5%(0402)EF | WTC | WR04X472 JTR | WALSIN TECHNOLOGY CORPORATION |
| CS03302FB03 | 2 | R59,R60 | RES CHIP 33 1/16W +-1%(0402)EF | WTC | WR04X33R0FTR | WALSIN TECHNOLOGY CORPORATION |
| BA05L060000 | 2 | U1,U2 | TRANS SMD DMN5L06K-7(50V,0.3A)SOT-23 | DDS | DMN5L06K-7 | DIODES TAIWAN CO.,LTD. |
| BAM70020089 | 2 | U3,U4 | TRANS MOSFET NX7002BKW(60V,0.24A,0.265W) | NXP | NX7002BKW | NXP semiconductors |
| AL009539K04 | 1 | U5 | IC CTRL(24P) TCA9539PWR(TSSOP) | TIC | TCA9539PWR | TEXAS INSTRUMENTS SUPPLY CO., |
| AL000075037 | 1 | U6 | IC(8P) LM75AD(SO8) | PHI | LM75AD | PHILIPS |
| AL022653002 | 1 | U7 | IC(6P) AP22653AW6-7(SOT26) | DDS | AP22653AW6-7 | DIODES TAIWAN CO.,LTD. |
| AL00SR05013 | 3 | U8,U10,U11 | IC(4P)SR05.TCT (SOT143)LF | STH | SR05.TCT | SILTRONTECH ELECTRONICS CORP. |
| AKE3C8B0Y14 | 1 | U9 | IC EEPROM(8P)24LC64T-I/SNG(SOIC) | MRP | 24LC64T-I/SNG | MICROCHIP TECHNOLOGY INC. |
| CS24702FB06 | 2 | R30,R31 | RES CHIP 4.7K 1/16W +-1%(0402)EF | WTC | WR04X4701FTR | WALSIN TECHNOLOGY CORPORATION |
| CS02202FB02 | 1 | R66 | RES CHIP 22 1/16W +-1%(0402)EF | WTC | WR04X22R0FTR | WALSIN TECHNOLOGY CORPORATION |
